# BASEBOARD_FAB2 (Tioga Pass) — schematic netlist excerpt (pin names and nets, part order shuffled) for the footprints in the layout excerpt that follows; sources: Cadence DE-HDL packaged netlist, KiCad conversion of Wiwynn_Tioga_Pass_MB.brd

R9E11  RES  200.0 1% CHIP  pkg 0402  page 187 : A = RST_PCIE_CPU_DEV2_R_N ; B = RST_PCIE_CPU_DEV2_N
C3P12  CAP  0.22UF 16V 10% X7R  pkg 0402  page 107 : A = P3E_CPU0_PE1_SS_TXN<0> ; B = P3E_CPU0_PE1_SS_C_TXN<0>
C6R6  CAP  10UF 16V 10% X6S  pkg 0805  page 203 : A = VR_FET_SW_P12V_STBY_PVCCIN_CPU0 ; B = GND

(kicad_pcb
	(version 20260206)
	(generator "pcbnew")
	(generator_version "10.0")
	(general
		(thickness 1.6)
		(legacy_teardrops no)
	)
	(paper "A4")
	(title_block
		(title "Wiwynn_Tioga_Pass_MB.brd")
		(comment 1 "Tioga Pass / footprints 2825-2827 of 4770")
	)
	(layers
		(0 "F.Cu" signal "TOP")
		(4 "In1.Cu" signal "L2GND")
		(6 "In2.Cu" signal "L3")
		(8 "In3.Cu" signal "L4GND")
		(10 "In4.Cu" signal "L5")
		(12 "In5.Cu" signal "L6GND")
		(14 "In6.Cu" signal "L7VCC")
		(16 "In7.Cu" signal "L8VCC")
		(18 "In8.Cu" signal "L9GND")
		(20 "In9.Cu" signal "L10")
		(22 "In10.Cu" signal "L11GND")
		(24 "In11.Cu" signal "L12")
		(26 "In12.Cu" signal "L13GND")
		(2 "B.Cu" signal "BOTTOM")
		(9 "F.Adhes" user "F.Adhesive")
		(11 "B.Adhes" user "B.Adhesive")
		(13 "F.Paste" user "Package Geometry/Pastemask Top")
		(15 "B.Paste" user "Package Geometry/Pastemask Bottom")
		(5 "F.SilkS" user "Ref Des/Silkscreen Top")
		(7 "B.SilkS" user "Ref Des/Silkscreen Bottom")
		(1 "F.Mask" user "Board Geometry/Soldermask Top")
		(3 "B.Mask" user "Board Geometry/Soldermask Bottom")
		(17 "Dwgs.User" user "User.Drawings")
		(19 "Cmts.User" user "User.Comments")
		(21 "Eco1.User" user "User.Eco1")
		(23 "Eco2.User" user "User.Eco2")
		(25 "Edge.Cuts" user "Board Geometry/Outline")
		(27 "Margin" user)
		(31 "F.CrtYd" user "Package Geometry/Place Bound Top")
		(29 "B.CrtYd" user "Package Geometry/Place Bound Bottom")
		(35 "F.Fab" user "Ref Des/Assembly Top")
		(33 "B.Fab" user "Ref Des/Assembly Bottom")
	)
	(footprint ""
		(layer "B.Cu")
		(at 467.868 -46.6725 180)
		(property "Reference" "R9E11"
			(at 0 0 0)
			(layer "B.SilkS")
			(hide yes)
			(effects
				(font
					(size 1.27 1.27)
				)
				(justify mirror)
			)
		)
		(property "Value" ""
			(at 0 0 0)
			(layer "B.Fab")
			(effects
				(font
					(size 1.27 1.27)
				)
				(justify mirror)
			)
		)
		(duplicate_pad_numbers_are_jumpers no)
		(fp_poly
			(pts
				(xy 0.2794 -0.1016) (xy -0.2794 -0.1016) (xy -0.2794 0.9906) (xy 0.2794 0.9906)
			)
			(stroke
				(width 0)
				(type default)
			)
			(fill no)
			(layer "B.CrtYd")
		)
		(fp_line
			(start 0.2794 0.9906)
			(end -0.2794 0.9906)
			(stroke
				(width 0.1)
				(type default)
			)
			(layer "B.Fab")
		)
		(fp_line
			(start 0.2794 -0.1016)
			(end 0.2794 0.9906)
			(stroke
				(width 0.1)
				(type default)
			)
			(layer "B.Fab")
		)
		(fp_line
			(start -0.2794 0.9906)
			(end -0.2794 -0.1016)
			(stroke
				(width 0.1)
				(type default)
			)
			(layer "B.Fab")
		)
		(fp_line
			(start -0.2794 -0.1016)
			(end 0.2794 -0.1016)
			(stroke
				(width 0.1)
				(type default)
			)
			(layer "B.Fab")
		)
		(pad "1" smd rect
			(at 0 0)
			(size 0.508 0.508)
			(layers "B.Cu" "B.Mask" "B.Paste")
			(net "RST_PCIE_CPU_DEV2_R_N")
		)
		(pad "2" smd rect
			(at 0 0.889)
			(size 0.508 0.508)
			(layers "B.Cu" "B.Mask" "B.Paste")
			(net "RST_PCIE_CPU_DEV2_N")
		)
		(zone
			(layer "B.Cu")
			(hatch none 0.5)
			(connect_pads
				(clearance 0)
			)
			(min_thickness 0.25)
			(keepout
				(tracks not_allowed)
				(vias allowed)
				(pads allowed)
				(copperpour not_allowed)
				(footprints allowed)
			)
			(placement
				(enabled no)
				(sheetname "")
			)
			(fill
				(thermal_gap 0.5)
				(thermal_bridge_width 0.5)
				(island_removal_mode 0)
			)
			(polygon
				(pts
					(xy 467.614 -47.3075) (xy 468.122 -47.3075) (xy 468.122 -46.9265) (xy 467.614 -46.9265)
				)
			)
		)
		(zone
			(layer "B.Cu")
			(hatch none 0.5)
			(connect_pads
				(clearance 0)
			)
			(min_thickness 0.25)
			(keepout
				(tracks allowed)
				(vias not_allowed)
				(pads allowed)
				(copperpour not_allowed)
				(footprints allowed)
			)
			(placement
				(enabled no)
				(sheetname "")
			)
			(fill
				(thermal_gap 0.5)
				(thermal_bridge_width 0.5)
				(island_removal_mode 0)
			)
			(polygon
				(pts
					(xy 467.614 -46.9265) (xy 468.122 -46.9265) (xy 468.122 -47.3075) (xy 467.614 -47.3075)
				)
			)
		)
	)
	(footprint ""
		(layer "B.Cu")
		(at 197.848728 -60.079382 90)
		(property "Reference" "C6R6"
			(at 0 0 90)
			(layer "B.SilkS")
			(hide yes)
			(effects
				(font
					(size 1.27 1.27)
				)
				(justify mirror)
			)
		)
		(property "Value" ""
			(at 0 0 90)
			(layer "B.Fab")
			(effects
				(font
					(size 1.27 1.27)
				)
				(justify mirror)
			)
		)
		(duplicate_pad_numbers_are_jumpers no)
		(fp_rect
			(start -0.7239 -0.2159)
			(end 0.7239 1.9939)
			(stroke
				(width 0)
				(type default)
			)
			(fill no)
			(layer "B.CrtYd")
		)
		(fp_line
			(start 0.7239 -0.2159)
			(end 0.7239 1.9939)
			(stroke
				(width 0.1)
				(type default)
			)
			(layer "B.Fab")
		)
		(fp_line
			(start -0.7239 -0.2159)
			(end 0.7239 -0.2159)
			(stroke
				(width 0.1)
				(type default)
			)
			(layer "B.Fab")
		)
		(fp_line
			(start 0.7239 1.9939)
			(end -0.7239 1.9939)
			(stroke
				(width 0.1)
				(type default)
			)
			(layer "B.Fab")
		)
		(fp_line
			(start -0.7239 1.9939)
			(end -0.7239 -0.2159)
			(stroke
				(width 0.1)
				(type default)
			)
			(layer "B.Fab")
		)
		(pad "1" smd rect
			(at 0 0 270)
			(size 1.27 1.016)
			(layers "B.Cu" "B.Mask" "B.Paste")
			(net "VR_FET_SW_P12V_STBY_PVCCIN_CPU0")
		)
		(pad "2" smd rect
			(at 0 1.778 270)
			(size 1.27 1.016)
			(layers "B.Cu" "B.Mask" "B.Paste")
			(net "GND")
		)
		(zone
			(layer "B.Cu")
			(hatch none 0.5)
			(connect_pads
				(clearance 0)
			)
			(min_thickness 0.25)
			(keepout
				(tracks not_allowed)
				(vias allowed)
				(pads allowed)
				(copperpour not_allowed)
				(footprints allowed)
			)
			(placement
				(enabled no)
				(sheetname "")
			)
			(fill
				(thermal_gap 0.5)
				(thermal_bridge_width 0.5)
				(island_removal_mode 0)
			)
			(polygon
				(pts
					(xy 198.356728 -59.444382) (xy 199.118728 -59.444382) (xy 199.118728 -60.714382) (xy 198.356728 -60.714382)
				)
			)
		)
	)
	(footprint ""
		(layer "B.Cu")
		(at 340.16696 -77.694536)
		(property "Reference" "C3P12"
			(at 0 0 0)
			(layer "B.SilkS")
			(hide yes)
			(effects
				(font
					(size 1.27 1.27)
				)
				(justify mirror)
			)
		)
		(property "Value" ""
			(at 0 0 0)
			(layer "B.Fab")
			(effects
				(font
					(size 1.27 1.27)
				)
				(justify mirror)
			)
		)
		(duplicate_pad_numbers_are_jumpers no)
		(fp_poly
			(pts
				(xy -0.3048 -0.1016) (xy -0.3048 0.9906) (xy 0.3048 0.9906) (xy 0.3048 -0.1016)
			)
			(stroke
				(width 0)
				(type default)
			)
			(fill no)
			(layer "B.CrtYd")
		)
		(fp_line
			(start -0.3048 -0.1016)
			(end 0.3048 -0.1016)
			(stroke
				(width 0.1)
				(type default)
			)
			(layer "B.Fab")
		)
		(fp_line
			(start -0.3048 0.9906)
			(end -0.3048 -0.1016)
			(stroke
				(width 0.1)
				(type default)
			)
			(layer "B.Fab")
		)
		(fp_line
			(start 0.3048 -0.1016)
			(end 0.3048 0.9906)
			(stroke
				(width 0.1)
				(type default)
			)
			(layer "B.Fab")
		)
		(fp_line
			(start 0.3048 0.9906)
			(end -0.3048 0.9906)
			(stroke
				(width 0.1)
				(type default)
			)
			(layer "B.Fab")
		)
		(pad "1" smd rect
			(at 0 0 180)
			(size 0.508 0.508)
			(layers "B.Cu" "B.Mask" "B.Paste")
			(net "P3E_CPU0_PE1_SS_TXN<0>")
		)
		(pad "2" smd rect
			(at 0 0.889 180)
			(size 0.508 0.508)
			(layers "B.Cu" "B.Mask" "B.Paste")
			(net "P3E_CPU0_PE1_SS_C_TXN<0>")
		)
		(zone
			(layer "B.Cu")
			(hatch none 0.5)
			(connect_pads
				(clearance 0)
			)
			(min_thickness 0.25)
			(keepout
				(tracks allowed)
				(vias not_allowed)
				(pads allowed)
				(copperpour not_allowed)
				(footprints allowed)
			)
			(placement
				(enabled no)
				(sheetname "")
			)
			(fill
				(thermal_gap 0.5)
				(thermal_bridge_width 0.5)
				(island_removal_mode 0)
			)
			(polygon
				(pts
					(xy 340.42096 -77.440536) (xy 339.91296 -77.440536) (xy 339.91296 -77.059536) (xy 340.42096 -77.059536)
				)
			)
		)
		(zone
			(layer "B.Cu")
			(hatch none 0.5)
			(connect_pads
				(clearance 0)
			)
			(min_thickness 0.25)
			(keepout
				(tracks not_allowed)
				(vias allowed)
				(pads allowed)
				(copperpour not_allowed)
				(footprints allowed)
			)
			(placement
				(enabled no)
				(sheetname "")
			)
			(fill
				(thermal_gap 0.5)
				(thermal_bridge_width 0.5)
				(island_removal_mode 0)
			)
			(polygon
				(pts
					(xy 340.42096 -77.059536) (xy 339.91296 -77.059536) (xy 339.91296 -77.440536) (xy 340.42096 -77.440536)
				)
			)
		)
	)
)
